(kicad_pcb
	(version 20260206)
	(generator "pcbnew")
	(generator_version "10.0")
	(general
		(thickness 1.21888)
		(legacy_teardrops no)
	)
	(paper "A4")
	(title_block
		(title "timecard-proto-v0 — Timingcard_PCB.PcbDoc")
		(comment 1 "Time Appliance Project (Time Card) / footprints 112-123 of 167")
	)
	(layers
		(0 "F.Cu" signal "TOP")
		(4 "In1.Cu" signal "SGND")
		(6 "In2.Cu" signal "IN1")
		(8 "In3.Cu" signal "IN2")
		(10 "In4.Cu" signal "SGND1")
		(2 "B.Cu" signal "BOTTOM")
		(9 "F.Adhes" user "F.Adhesive")
		(11 "B.Adhes" user "B.Adhesive")
		(13 "F.Paste" user "Top Paste")
		(15 "B.Paste" user "Bottom Paste")
		(5 "F.SilkS" user "Top Overlay")
		(7 "B.SilkS" user "Bottom Overlay")
		(1 "F.Mask" user "Top Solder")
		(3 "B.Mask" user "Bottom Solder")
		(17 "Dwgs.User" user "User.Drawings")
		(19 "Cmts.User" user "User.Comments")
		(21 "Eco1.User" user "User.Eco1")
		(23 "Eco2.User" user "User.Eco2")
		(25 "Edge.Cuts" user)
		(27 "Margin" user)
		(31 "F.CrtYd" user "Top Courtyard")
		(29 "B.CrtYd" user "Bottom Courtyard")
		(35 "F.Fab" user "Top Component Center")
		(33 "B.Fab" user "Bottom Component Center")
	)
	(footprint "Modules:MAC-SA5X"
		(layer "F.Cu")
		(at 154.473665 92.25689 -90)
		(property "Reference" "U10"
			(at -0.535035 -47.59124 0)
			(unlocked yes)
			(layer "F.SilkS")
			(effects
				(font
					(size 0.762 0.762)
					(thickness 0.2286)
				)
				(justify left bottom)
			)
		)
		(property "Value" "MAC-SA5X"
			(at 27.98699 25.2857 0)
			(unlocked yes)
			(layer "F.SilkS")
			(hide yes)
			(effects
				(font
					(size 1.524 1.524)
					(thickness 0.254)
				)
				(justify left bottom)
			)
		)
		(sheetname "MAC")
		(sheetfile "MAC.kicad_sch")
		(duplicate_pad_numbers_are_jumpers no)
		(fp_line
			(start 0 0)
			(end 0 -50.8)
			(stroke
				(width 0.254)
				(type solid)
			)
			(layer "F.SilkS")
		)
		(fp_line
			(start 50.8 0)
			(end 0 0)
			(stroke
				(width 0.254)
				(type solid)
			)
			(layer "F.SilkS")
		)
		(fp_line
			(start 50.8 0)
			(end 50.8 -50.8)
			(stroke
				(width 0.254)
				(type solid)
			)
			(layer "F.SilkS")
		)
		(fp_line
			(start 50.8 -50.8)
			(end 0 -50.8)
			(stroke
				(width 0.254)
				(type solid)
			)
			(layer "F.SilkS")
		)
		(fp_circle
			(center 27.69128 -8.78503)
			(end 27.56428 -8.78503)
			(stroke
				(width 0.254)
				(type solid)
			)
			(fill no)
			(layer "F.SilkS")
		)
		(pad "1" smd rect
			(at 27.69128 -7.36503 90)
			(size 0.25 1.8)
			(layers "F.Cu" "F.Mask" "F.Paste")
			(net "MAC_PPS_IN1+")
		)
		(pad "2" smd rect
			(at 27.69128 -3.36503 90)
			(size 0.25 1.8)
			(layers "F.Cu" "F.Mask" "F.Paste")
			(net "MAC_USB+")
		)
		(pad "3" smd rect
			(at 27.18328 -7.36503 90)
			(size 0.25 1.8)
			(layers "F.Cu" "F.Mask" "F.Paste")
			(net "MAC_PPS_IN1-")
		)
		(pad "4" smd rect
			(at 27.18328 -3.36503 90)
			(size 0.25 1.8)
			(layers "F.Cu" "F.Mask" "F.Paste")
			(net "MAC_USB-")
		)
		(pad "5" smd rect
			(at 26.67528 -7.36503 90)
			(size 0.25 1.8)
			(layers "F.Cu" "F.Mask" "F.Paste")
			(net "MAC_PPS_IN0+")
		)
		(pad "6" smd rect
			(at 26.67528 -3.36503 90)
			(size 0.25 1.8)
			(layers "F.Cu" "F.Mask" "F.Paste")
			(net "MAC_USB_PWR")
		)
		(pad "7" smd rect
			(at 26.16728 -7.36503 90)
			(size 0.25 1.8)
			(layers "F.Cu" "F.Mask" "F.Paste")
			(net "MAC_PPS_IN0-")
		)
		(pad "8" smd rect
			(at 26.16728 -3.36503 90)
			(size 0.25 1.8)
			(layers "F.Cu" "F.Mask" "F.Paste")
			(net "GND")
		)
		(pad "9" smd rect
			(at 25.65928 -7.36503 90)
			(size 0.25 1.8)
			(layers "F.Cu" "F.Mask" "F.Paste")
			(net "GND")
		)
		(pad "10" smd rect
			(at 25.65928 -3.36503 90)
			(size 0.25 1.8)
			(layers "F.Cu" "F.Mask" "F.Paste")
		)
		(pad "11" smd rect
			(at 25.15128 -7.36503 90)
			(size 0.25 1.8)
			(layers "F.Cu" "F.Mask" "F.Paste")
		)
		(pad "12" smd rect
			(at 25.15128 -3.36503 90)
			(size 0.25 1.8)
			(layers "F.Cu" "F.Mask" "F.Paste")
		)
		(pad "13" smd rect
			(at 24.64328 -7.36503 90)
			(size 0.25 1.8)
			(layers "F.Cu" "F.Mask" "F.Paste")
		)
		(pad "14" smd rect
			(at 24.64328 -3.36503 90)
			(size 0.25 1.8)
			(layers "F.Cu" "F.Mask" "F.Paste")
		)
		(pad "15" smd rect
			(at 24.13528 -7.36503 90)
			(size 0.25 1.8)
			(layers "F.Cu" "F.Mask" "F.Paste")
			(net "GND")
		)
		(pad "16" smd rect
			(at 24.13528 -3.36503 90)
			(size 0.25 1.8)
			(layers "F.Cu" "F.Mask" "F.Paste")
		)
		(pad "17" smd rect
			(at 23.62728 -7.36503 90)
			(size 0.25 1.8)
			(layers "F.Cu" "F.Mask" "F.Paste")
			(net "MAC_PPS_OUT+")
		)
		(pad "18" smd rect
			(at 23.62728 -3.36503 90)
			(size 0.25 1.8)
			(layers "F.Cu" "F.Mask" "F.Paste")
		)
		(pad "19" smd rect
			(at 23.11928 -7.36503 90)
			(size 0.25 1.8)
			(layers "F.Cu" "F.Mask" "F.Paste")
			(net "MAC_PPS_OUT-")
		)
		(pad "20" smd rect
			(at 23.11928 -3.36503 90)
			(size 0.25 1.8)
			(layers "F.Cu" "F.Mask" "F.Paste")
			(net "MAC_ALARM")
		)
		(pad "P1" thru_hole circle
			(at 45.7 -45.7 270)
			(size 1.905 1.905)
			(drill 1.27)
			(layers "*.Cu" "*.Mask")
			(remove_unused_layers no)
			(net "MAC_10Mout")
			(thermal_bridge_angle 90)
		)
		(pad "P2" thru_hole circle
			(at 25.4 -45.7 270)
			(size 1.905 1.905)
			(drill 1.27)
			(layers "*.Cu" "*.Mask")
			(remove_unused_layers no)
			(net "GND")
			(thermal_bridge_angle 90)
		)
		(pad "P3" thru_hole circle
			(at 5.1 -45.7 270)
			(size 1.905 1.905)
			(drill 1.27)
			(layers "*.Cu" "*.Mask")
			(remove_unused_layers no)
			(net "MAC_10Mout")
			(thermal_bridge_angle 90)
		)
		(pad "P4" thru_hole circle
			(at 5.1 -5.1 270)
			(size 1.905 1.905)
			(drill 1.27)
			(layers "*.Cu" "*.Mask")
			(remove_unused_layers no)
			(net "GND")
			(thermal_bridge_angle 90)
		)
		(pad "P5" thru_hole circle
			(at 45.7 -5.1 270)
			(size 1.905 1.905)
			(drill 1.27)
			(layers "*.Cu" "*.Mask")
			(remove_unused_layers no)
			(net "+5.0V")
			(thermal_bridge_angle 90)
		)
		(pad "P6" thru_hole circle
			(at 2.4 -7.2 270)
			(size 1.905 1.905)
			(drill 1.27)
			(layers "*.Cu" "*.Mask")
			(remove_unused_layers no)
			(net "MAC_BITE")
			(thermal_bridge_angle 90)
		)
		(pad "P7" thru_hole circle
			(at 2.4 -10.2 270)
			(size 1.905 1.905)
			(drill 1.27)
			(layers "*.Cu" "*.Mask")
			(remove_unused_layers no)
			(net "MAC_RX")
			(thermal_bridge_angle 90)
		)
		(pad "P8" thru_hole circle
			(at 2.4 -13.2 270)
			(size 1.905 1.905)
			(drill 1.27)
			(layers "*.Cu" "*.Mask")
			(remove_unused_layers no)
			(net "MAC_TX")
			(thermal_bridge_angle 90)
		)
	)
	(footprint "Resistors:RESC1608X50N"
		(layer "F.Cu")
		(at 190.288595 53.6786)
		(property "Reference" "R34"
			(at 1.6 0.393345 0)
			(unlocked yes)
			(layer "F.SilkS")
			(effects
				(font
					(size 0.762 0.762)
					(thickness 0.2286)
				)
				(justify left bottom)
			)
		)
		(property "Value" "ERJ-3EKF1002V"
			(at -0.4445 3.72999 0)
			(unlocked yes)
			(layer "F.SilkS")
			(hide yes)
			(effects
				(font
					(size 1.524 1.524)
					(thickness 0.254)
				)
				(justify left bottom)
			)
		)
		(sheetname "USER_IO")
		(sheetfile "USER_IO.kicad_sch")
		(duplicate_pad_numbers_are_jumpers no)
		(fp_line
			(start 0 0.5)
			(end 0 -0.5)
			(stroke
				(width 0.1524)
				(type solid)
			)
			(layer "F.SilkS")
		)
		(pad "1" smd rect
			(at -0.69 0 90)
			(size 1 0.72)
			(layers "F.Cu" "F.Mask" "F.Paste")
			(net "NetR34_1")
		)
		(pad "2" smd rect
			(at 0.69 0 90)
			(size 1 0.72)
			(layers "F.Cu" "F.Mask" "F.Paste")
			(net "+3.3V")
		)
	)
	(footprint "Passives:DIOM6959X26N"
		(layer "F.Cu")
		(at 85.027595 124.2296 180)
		(property "Reference" "D17"
			(at 4.1402 4.097655 0)
			(unlocked yes)
			(layer "F.SilkS")
			(effects
				(font
					(size 0.762 0.762)
					(thickness 0.2286)
				)
				(justify left bottom)
			)
		)
		(property "Value" "SMCJ6.5CA"
			(at 4.2545 -5.91439 0)
			(unlocked yes)
			(layer "F.SilkS")
			(hide yes)
			(effects
				(font
					(size 1.524 1.524)
					(thickness 0.254)
				)
				(justify left bottom)
			)
		)
		(sheetname "USER_IO")
		(sheetfile "USER_IO.kicad_sch")
		(duplicate_pad_numbers_are_jumpers no)
		(fp_line
			(start 3.6 3.15)
			(end -3.6 3.15)
			(stroke
				(width 0.2)
				(type solid)
			)
			(layer "F.SilkS")
		)
		(fp_line
			(start 3.6 1.975)
			(end 3.6 3.15)
			(stroke
				(width 0.2)
				(type solid)
			)
			(layer "F.SilkS")
		)
		(fp_line
			(start 3.6 -3.15)
			(end 3.6 -1.975)
			(stroke
				(width 0.2)
				(type solid)
			)
			(layer "F.SilkS")
		)
		(fp_line
			(start 3.6 -3.15)
			(end -3.6 -3.15)
			(stroke
				(width 0.2)
				(type solid)
			)
			(layer "F.SilkS")
		)
		(fp_line
			(start -3.6 1.975)
			(end -3.6 3.15)
			(stroke
				(width 0.2)
				(type solid)
			)
			(layer "F.SilkS")
		)
		(fp_line
			(start -3.6 -3.15)
			(end -3.6 -1.975)
			(stroke
				(width 0.2)
				(type solid)
			)
			(layer "F.SilkS")
		)
		(fp_circle
			(center -4.25 -2.125)
			(end -4.25 -2)
			(stroke
				(width 0.25)
				(type solid)
			)
			(fill no)
			(layer "F.SilkS")
		)
		(pad "A" smd rect
			(at 2.85 0 270)
			(size 3.15 2.45)
			(layers "F.Cu" "F.Mask" "F.Paste")
			(net "ANT3")
		)
		(pad "K" smd rect
			(at -2.85 0 270)
			(size 3.15 2.45)
			(layers "F.Cu" "F.Mask" "F.Paste")
			(net "GND")
		)
	)
	(footprint "Resistors:RESC1608X50N"
		(layer "F.Cu")
		(at 147.511595 89.5332)
		(property "Reference" "R42"
			(at -1.47271 2.696655 0)
			(unlocked yes)
			(layer "F.SilkS")
			(effects
				(font
					(size 0.762 0.762)
					(thickness 0.2286)
				)
				(justify left bottom)
			)
		)
		(property "Value" "ERJ-3EKF1002V"
			(at -0.4445 3.72999 0)
			(unlocked yes)
			(layer "F.SilkS")
			(hide yes)
			(effects
				(font
					(size 1.524 1.524)
					(thickness 0.254)
				)
				(justify left bottom)
			)
		)
		(sheetname "MAC")
		(sheetfile "MAC.kicad_sch")
		(duplicate_pad_numbers_are_jumpers no)
		(fp_line
			(start 0 0.5)
			(end 0 -0.5)
			(stroke
				(width 0.1524)
				(type solid)
			)
			(layer "F.SilkS")
		)
		(pad "1" smd rect
			(at -0.69 0 90)
			(size 1 0.72)
			(layers "F.Cu" "F.Mask" "F.Paste")
			(net "NetR42_1")
		)
		(pad "2" smd rect
			(at 0.69 0 90)
			(size 1 0.72)
			(layers "F.Cu" "F.Mask" "F.Paste")
			(net "+3.3V_CLEAN")
		)
	)
	(footprint "Vault:CAPC1608X87X45ML20T05"
		(layer "F.Cu")
		(at 112.840595 67.0796 -90)
		(property "Reference" "C59"
			(at -2.001 -0.441345 90)
			(unlocked yes)
			(layer "F.SilkS")
			(effects
				(font
					(size 0.762 0.762)
					(thickness 0.2286)
				)
				(justify left bottom)
			)
		)
		(property "Value" "0.1uF"
			(at 3.47599 0.2921 0)
			(unlocked yes)
			(layer "F.SilkS")
			(hide yes)
			(effects
				(font
					(size 1.524 1.524)
					(thickness 0.254)
				)
				(justify left bottom)
			)
		)
		(sheetname "GPS_IMU_SENSORS")
		(sheetfile "GPS_IMU_SENSORS.kicad_sch")
		(duplicate_pad_numbers_are_jumpers no)
		(pad "1" smd rect
			(at -0.7 0)
			(size 1.1 1.05)
			(layers "F.Cu" "F.Mask" "F.Paste")
			(net "GND")
		)
		(pad "2" smd rect
			(at 0.7 0)
			(size 1.1 1.05)
			(layers "F.Cu" "F.Mask" "F.Paste")
			(net "+3.3V")
		)
	)
	(footprint "Connectors:3PINV-100"
		(layer "F.Cu")
		(at 110.388595 52.4286 -90)
		(property "Reference" "JP2"
			(at 6.925 1.431655 90)
			(unlocked yes)
			(layer "F.SilkS")
			(effects
				(font
					(size 0.762 0.762)
					(thickness 0.2286)
				)
				(justify left bottom)
			)
		)
		(property "Value" "JUMPER_3PIN"
			(at 9.49579 1.7145 0)
			(unlocked yes)
			(layer "F.SilkS")
			(hide yes)
			(effects
				(font
					(size 1.524 1.524)
					(thickness 0.254)
				)
				(justify left bottom)
			)
		)
		(sheetname "GPS_IMU_SENSORS")
		(sheetfile "GPS_IMU_SENSORS.kicad_sch")
		(duplicate_pad_numbers_are_jumpers no)
		(fp_line
			(start -1.27 1.27)
			(end -1.27 -1.27)
			(stroke
				(width 0.1524)
				(type solid)
			)
			(layer "F.SilkS")
		)
		(fp_line
			(start 6.35 1.27)
			(end -1.27 1.27)
			(stroke
				(width 0.1524)
				(type solid)
			)
			(layer "F.SilkS")
		)
		(fp_line
			(start 6.35 1.27)
			(end 6.35 -1.27)
			(stroke
				(width 0.1524)
				(type solid)
			)
			(layer "F.SilkS")
		)
		(fp_line
			(start 6.35 -1.27)
			(end -1.27 -1.27)
			(stroke
				(width 0.1524)
				(type solid)
			)
			(layer "F.SilkS")
		)
		(pad "1" thru_hole rect
			(at 0 0 270)
			(size 1.397 1.397)
			(drill 0.762)
			(layers "*.Cu" "*.Mask")
			(remove_unused_layers no)
			(net "GPS1_RX")
		)
		(pad "2" thru_hole circle
			(at 2.54 0 270)
			(size 1.397 1.397)
			(drill 0.762)
			(layers "*.Cu" "*.Mask")
			(remove_unused_layers no)
			(net "NetJP2_2")
			(thermal_bridge_angle 90)
		)
		(pad "3" thru_hole circle
			(at 5.08 0 270)
			(size 1.397 1.397)
			(drill 0.762)
			(layers "*.Cu" "*.Mask")
			(remove_unused_layers no)
			(net "NetJP2_3")
			(thermal_bridge_angle 90)
		)
	)
	(footprint "Vault:RESC1608X55X30NL15T15"
		(layer "F.Cu")
		(at 85.088595 56.9786 90)
		(property "Reference" "R29"
			(at -1.2 -1.206655 90)
			(unlocked yes)
			(layer "F.SilkS")
			(effects
				(font
					(size 0.762 0.762)
					(thickness 0.2286)
				)
				(justify left bottom)
			)
		)
		(property "Value" "200 OHM"
			(at -3.72999 -0.4445 0)
			(unlocked yes)
			(layer "F.SilkS")
			(hide yes)
			(effects
				(font
					(size 1.524 1.524)
					(thickness 0.254)
				)
				(justify left bottom)
			)
		)
		(sheetname "USER_IO")
		(sheetfile "USER_IO.kicad_sch")
		(duplicate_pad_numbers_are_jumpers no)
		(pad "1" smd rect
			(at -0.675 0 180)
			(size 0.95 0.8)
			(layers "F.Cu" "F.Mask" "F.Paste")
			(net "LED3")
		)
		(pad "2" smd rect
			(at 0.675 0 180)
			(size 0.95 0.8)
			(layers "F.Cu" "F.Mask" "F.Paste")
			(net "NetD13_1")
		)
	)
	(footprint "Miscellaneous:OMRON-B3U-1000P"
		(layer "F.Cu")
		(at 186.119595 53.7446)
		(property "Reference" "S6"
			(at -2.3622 -2.218055 0)
			(unlocked yes)
			(layer "F.SilkS")
			(effects
				(font
					(size 0.762 0.762)
					(thickness 0.2286)
				)
				(justify left bottom)
			)
		)
		(property "Value" "B3U-1000P"
			(at -2.3241 4.03479 0)
			(unlocked yes)
			(layer "F.SilkS")
			(hide yes)
			(effects
				(font
					(size 1.524 1.524)
					(thickness 0.254)
				)
				(justify left bottom)
			)
		)
		(sheetname "USER_IO")
		(sheetfile "USER_IO.kicad_sch")
		(duplicate_pad_numbers_are_jumpers no)
		(fp_line
			(start -2.286 -1.397)
			(end 2.286 -1.397)
			(stroke
				(width 0.2032)
				(type solid)
			)
			(layer "F.SilkS")
		)
		(fp_line
			(start -2.286 -1.143)
			(end -2.286 -1.397)
			(stroke
				(width 0.2032)
				(type solid)
			)
			(layer "F.SilkS")
		)
		(fp_line
			(start -2.286 1.397)
			(end -2.286 1.143)
			(stroke
				(width 0.2032)
				(type solid)
			)
			(layer "F.SilkS")
		)
		(fp_line
			(start -2.286 1.397)
			(end 2.286 1.397)
			(stroke
				(width 0.2032)
				(type solid)
			)
			(layer "F.SilkS")
		)
		(fp_line
			(start 2.286 -1.143)
			(end 2.286 -1.397)
			(stroke
				(width 0.2032)
				(type solid)
			)
			(layer "F.SilkS")
		)
		(fp_line
			(start 2.286 1.397)
			(end 2.286 1.143)
			(stroke
				(width 0.2032)
				(type solid)
			)
			(layer "F.SilkS")
		)
		(pad "1" smd rect
			(at -1.7 0)
			(size 0.8 1.7)
			(layers "F.Cu" "F.Mask" "F.Paste")
			(net "GND")
		)
		(pad "2" smd rect
			(at 1.7 0)
			(size 0.8 1.7)
			(layers "F.Cu" "F.Mask" "F.Paste")
			(net "NetR34_1")
		)
	)
	(footprint "Miscellaneous Devices:J1-0603"
		(layer "F.Cu")
		(at 119.138595 86.1786 -90)
		(property "Reference" "R17"
			(at -2.358749 -0.85179 0)
			(unlocked yes)
			(layer "F.SilkS")
			(effects
				(font
					(size 0.762 0.762)
					(thickness 0.254)
				)
			)
		)
		(property "Value" "MACPPS"
			(at 2.835402 -4.227705 0)
			(unlocked yes)
			(layer "F.SilkS")
			(hide yes)
			(effects
				(font
					(size 1.524 1.524)
					(thickness 0.254)
				)
			)
		)
		(sheetname "MAC")
		(sheetfile "MAC.kicad_sch")
		(duplicate_pad_numbers_are_jumpers no)
		(fp_line
			(start 0.2 0.35)
			(end -0.2 0.35)
			(stroke
				(width 0.2)
				(type solid)
			)
			(layer "F.SilkS")
		)
		(fp_line
			(start 0.2 -0.35)
			(end -0.2 -0.35)
			(stroke
				(width 0.2)
				(type solid)
			)
			(layer "F.SilkS")
		)
		(pad "1" smd rect
			(at -0.75 0)
			(size 0.9 0.7)
			(layers "F.Cu" "F.Mask" "F.Paste")
			(net "GPS1_TP1")
		)
		(pad "2" smd rect
			(at 0.75 0)
			(size 0.9 0.7)
			(layers "F.Cu" "F.Mask" "F.Paste")
			(net "MAC_PPS_IN0+")
		)
	)
	(footprint "Capacitors:CAPC2012X14N"
		(layer "F.Cu")
		(at 114.618595 67.0796 90)
		(property "Reference" "C58"
			(at 2.08329 0.664665 90)
			(unlocked yes)
			(layer "F.SilkS")
			(effects
				(font
					(size 0.762 0.762)
					(thickness 0.2286)
				)
				(justify left bottom)
			)
		)
		(property "Value" "CAP_0805_10UF_25V"
			(at -3.52679 -1.5875 0)
			(unlocked yes)
			(layer "F.SilkS")
			(hide yes)
			(effects
				(font
					(size 1.524 1.524)
					(thickness 0.254)
				)
				(justify left bottom)
			)
		)
		(sheetname "GPS_IMU_SENSORS")
		(sheetfile "GPS_IMU_SENSORS.kicad_sch")
		(duplicate_pad_numbers_are_jumpers no)
		(fp_line
			(start -0.762 -0.9652)
			(end 0.762 -0.9652)
			(stroke
				(width 0.1524)
				(type solid)
			)
			(layer "F.SilkS")
		)
		(fp_line
			(start -0.762 0.9652)
			(end 0.762 0.9652)
			(stroke
				(width 0.1524)
				(type solid)
			)
			(layer "F.SilkS")
		)
		(pad "1" smd rect
			(at -0.9 0 180)
			(size 1.45 1.15)
			(layers "F.Cu" "F.Mask" "F.Paste")
			(net "+3.3V")
		)
		(pad "2" smd rect
			(at 0.9 0 180)
			(size 1.45 1.15)
			(layers "F.Cu" "F.Mask" "F.Paste")
			(net "GND")
		)
	)
	(footprint "Resistors:RESC1608X50N"
		(layer "F.Cu")
		(at 113.018395 93.2162 90)
		(property "Reference" "R22"
			(at -0.9624 -1.036455 90)
			(unlocked yes)
			(layer "F.SilkS")
			(effects
				(font
					(size 0.762 0.762)
					(thickness 0.2286)
				)
				(justify left bottom)
			)
		)
		(property "Value" "ERJ-3EKF4701V"
			(at -3.72999 -0.4445 0)
			(unlocked yes)
			(layer "F.SilkS")
			(hide yes)
			(effects
				(font
					(size 1.524 1.524)
					(thickness 0.254)
				)
				(justify left bottom)
			)
		)
		(sheetname "PCIe_JTAG")
		(sheetfile "PCIe_JTAG.kicad_sch")
		(duplicate_pad_numbers_are_jumpers no)
		(fp_line
			(start 0 -0.5)
			(end 0 0.5)
			(stroke
				(width 0.1524)
				(type solid)
			)
			(layer "F.SilkS")
		)
		(pad "1" smd rect
			(at -0.69 0 180)
			(size 1 0.72)
			(layers "F.Cu" "F.Mask" "F.Paste")
			(net "PCIE_PERST")
		)
		(pad "2" smd rect
			(at 0.69 0 180)
			(size 1 0.72)
			(layers "F.Cu" "F.Mask" "F.Paste")
			(net "+3.3V")
		)
	)
	(footprint "Resistors:RESC1608X50N"
		(layer "F.Cu")
		(at 229.934595 106.8306 90)
		(property "Reference" "R2"
			(at 1.477 0.522345 90)
			(unlocked yes)
			(layer "F.SilkS")
			(effects
				(font
					(size 0.762 0.762)
					(thickness 0.2286)
				)
				(justify left bottom)
			)
		)
		(property "Value" "ERJ-3EKF4702V"
			(at -3.04419 -4.4323 0)
			(unlocked yes)
			(layer "F.SilkS")
			(hide yes)
			(effects
				(font
					(size 1.524 1.524)
					(thickness 0.254)
				)
				(justify left bottom)
			)
		)
		(sheetname "POWER")
		(sheetfile "POWER.kicad_sch")
		(duplicate_pad_numbers_are_jumpers no)
		(fp_line
			(start 0 -0.5)
			(end 0 0.5)
			(stroke
				(width 0.1524)
				(type solid)
			)
			(layer "F.SilkS")
		)
		(pad "1" smd rect
			(at -0.69 0 180)
			(size 1 0.72)
			(layers "F.Cu" "F.Mask" "F.Paste")
			(net "NetR2_1")
		)
		(pad "2" smd rect
			(at 0.69 0 180)
			(size 1 0.72)
			(layers "F.Cu" "F.Mask" "F.Paste")
			(net "+12V")
		)
	)
)
